# TIMECARD (Time Appliance Project (Time Card)) — schematic netlist excerpt (pin names and nets, part order shuffled) for the footprints in the layout excerpt that follows; sources: Cadence DE-HDL packaged netlist, KiCad conversion of R4006-B0001-02_R01.brd

C49  CAPACITOR  0.022UF 10%  pkg SMC_0402R_H022  page 28 : \1\ = XP3R3V_SS ; \2\ = XP3R3V_AGND
TP203  TP_PIONT  pkg TP010CT020B030_PTH  page 25 : \1\ = IO_L24P_35

(kicad_pcb
	(version 20260206)
	(generator "pcbnew")
	(generator_version "10.0")
	(general
		(thickness 1.6)
		(legacy_teardrops no)
	)
	(paper "A4")
	(title_block
		(title "timecard-production-celestica-r4006 — R4006-B0001-02_R01.brd")
		(comment 1 "Time Appliance Project (Time Card) / footprints 604-605 of 1113")
	)
	(layers
		(0 "F.Cu" signal "TOP")
		(4 "In1.Cu" signal "L02_GND1")
		(6 "In2.Cu" signal "L03_SIG1")
		(8 "In3.Cu" signal "L04_GND2")
		(10 "In4.Cu" signal "L05_VCC1")
		(12 "In5.Cu" signal "L06_VCC2")
		(14 "In6.Cu" signal "L07_GND3")
		(16 "In7.Cu" signal "L08_SIG2")
		(18 "In8.Cu" signal "L09_GND4")
		(2 "B.Cu" signal "BOTTOM")
		(9 "F.Adhes" user "F.Adhesive")
		(11 "B.Adhes" user "B.Adhesive")
		(13 "F.Paste" user "Package Geometry/Pastemask Top")
		(15 "B.Paste" user "Package Geometry/Pastemask Bottom")
		(5 "F.SilkS" user "Ref Des/Silkscreen Top")
		(7 "B.SilkS" user "Ref Des/Silkscreen Bottom")
		(1 "F.Mask" user "Board Geometry/Soldermask Top")
		(3 "B.Mask" user "Board Geometry/Soldermask Bottom")
		(17 "Dwgs.User" user "User.Drawings")
		(19 "Cmts.User" user "User.Comments")
		(21 "Eco1.User" user "User.Eco1")
		(23 "Eco2.User" user "User.Eco2")
		(25 "Edge.Cuts" user "Board Geometry/Outline")
		(27 "Margin" user)
		(31 "F.CrtYd" user "Package Geometry/Place Bound Top")
		(29 "B.CrtYd" user "Package Geometry/Place Bound Bottom")
		(35 "F.Fab" user "Ref Des/Assembly Top")
		(33 "B.Fab" user "Ref Des/Assembly Bottom")
	)
	(footprint ""
		(layer "F.Cu")
		(at 119.6848 -29.3878 90)
		(property "Reference" "TP203"
			(at -4.1656 1.12395 90)
			(unlocked yes)
			(layer "F.SilkS")
			(effects
				(font
					(size 0.635 0.4064)
					(thickness 0.1524)
				)
				(justify left)
			)
		)
		(property "Value" ""
			(at 0 0 90)
			(layer "F.Fab")
			(effects
				(font
					(size 1.27 1.27)
				)
			)
		)
		(property "Device Type" "TP_PIONT-TP010CT020B030_PTH-TPA"
			(at -1.341882 0.996696 90)
			(unlocked yes)
			(layer "F.Fab")
			(hide yes)
			(effects
				(font
					(size 0.7874 0.5842)
					(thickness 0.1524)
				)
				(justify left)
			)
		)
		(duplicate_pad_numbers_are_jumpers no)
		(fp_poly
			(pts
				(arc
					(start 0 0.889)
					(mid 0 -0.889)
					(end 0 0.889)
				)
			)
			(stroke
				(width 0)
				(type default)
			)
			(fill no)
			(layer "B.CrtYd")
		)
		(fp_poly
			(pts
				(arc
					(start 0 0.889)
					(mid 0 -0.889)
					(end 0 0.889)
				)
			)
			(stroke
				(width 0)
				(type default)
			)
			(fill no)
			(layer "F.CrtYd")
		)
		(pad "1" thru_hole circle
			(at 0 0 90)
			(size 0.508 0.508)
			(drill 0.254)
			(layers "*.Cu" "*.Mask")
			(remove_unused_layers no)
			(net "IO_L24P_35")
			(clearance 0.1016)
			(padstack
				(mode front_inner_back)
				(layer "Inner"
					(shape circle)
					(size 0.508 0.508)
					(clearance 0.1016)
				)
				(layer "B.Cu"
					(shape circle)
					(size 0.762 0.762)
					(clearance -0.0254)
				)
			)
		)
	)
	(footprint ""
		(layer "F.Cu")
		(at 89.9922 -101.2698)
		(property "Reference" "C49"
			(at 3.048 0.16637 0)
			(unlocked yes)
			(layer "F.SilkS")
			(effects
				(font
					(size 0.7874 0.5842)
					(thickness 0.1524)
				)
			)
		)
		(property "Value" "VAL*"
			(at 0.0762 2.067306 0)
			(unlocked yes)
			(layer "F.Fab")
			(hide yes)
			(effects
				(font
					(size 0.7874 0.5842)
					(thickness 0.1524)
				)
			)
		)
		(property "Tolerance" "TOL*"
			(at 0.0762 3.032506 0)
			(unlocked yes)
			(layer "Cmts.User")
			(hide yes)
			(effects
				(font
					(size 0.7874 0.5842)
					(thickness 0.1524)
				)
			)
		)
		(property "User Part Number" "PARTNUM*"
			(at 0.1016 4.023106 0)
			(unlocked yes)
			(layer "Cmts.User")
			(hide yes)
			(effects
				(font
					(size 0.7874 0.5842)
					(thickness 0.1524)
				)
			)
		)
		(property "Device Type" "CAPACITOR-G105-0B223-EK,0.022UA"
			(at 0.0508 1.127506 0)
			(unlocked yes)
			(layer "F.Fab")
			(hide yes)
			(effects
				(font
					(size 0.7874 0.5842)
					(thickness 0.1524)
				)
			)
		)
		(duplicate_pad_numbers_are_jumpers no)
		(fp_line
			(start -1.143 -0.5588)
			(end -1.143 0.5588)
			(stroke
				(width 0.1)
				(type default)
			)
			(layer "F.SilkS")
		)
		(fp_line
			(start -1.143 0.5588)
			(end 1.143 0.5588)
			(stroke
				(width 0.1)
				(type default)
			)
			(layer "F.SilkS")
		)
		(fp_line
			(start 1.143 -0.5588)
			(end -1.143 -0.5588)
			(stroke
				(width 0.1)
				(type default)
			)
			(layer "F.SilkS")
		)
		(fp_line
			(start 1.143 0.5588)
			(end 1.143 -0.5588)
			(stroke
				(width 0.1)
				(type default)
			)
			(layer "F.SilkS")
		)
		(fp_rect
			(start -1.143 0.5588)
			(end 1.143 -0.5588)
			(stroke
				(width 0)
				(type default)
			)
			(fill no)
			(layer "F.CrtYd")
		)
		(fp_line
			(start -0.508 -0.3048)
			(end -0.508 0.3048)
			(stroke
				(width 0.1)
				(type default)
			)
			(layer "F.Fab")
		)
		(fp_line
			(start -0.508 0.3048)
			(end 0.508 0.3048)
			(stroke
				(width 0.1)
				(type default)
			)
			(layer "F.Fab")
		)
		(fp_line
			(start 0.508 -0.3048)
			(end -0.508 -0.3048)
			(stroke
				(width 0.1)
				(type default)
			)
			(layer "F.Fab")
		)
		(fp_line
			(start 0.508 0.3048)
			(end 0.508 -0.3048)
			(stroke
				(width 0.1)
				(type default)
			)
			(layer "F.Fab")
		)
		(pad "1" smd rect
			(at -0.5334 0)
			(size 0.7112 0.6096)
			(layers "F.Cu" "F.Mask" "F.Paste")
			(net "XP3R3V_SS")
		)
		(pad "2" smd rect
			(at 0.5334 0)
			(size 0.7112 0.6096)
			(layers "F.Cu" "F.Mask" "F.Paste")
			(net "XP3R3V_AGND")
		)
		(zone
			(layer "F.Cu")
			(hatch none 0.5)
			(connect_pads
				(clearance 0)
			)
			(min_thickness 0.25)
			(keepout
				(tracks allowed)
				(vias not_allowed)
				(pads allowed)
				(copperpour not_allowed)
				(footprints allowed)
			)
			(placement
				(enabled no)
				(sheetname "")
			)
			(fill
				(thermal_gap 0.5)
				(thermal_bridge_width 0.5)
				(island_removal_mode 0)
			)
			(polygon
				(pts
					(xy 89.916 -100.965) (xy 90.0684 -100.965) (xy 90.0684 -101.5746) (xy 89.916 -101.5746)
				)
			)
		)
	)
)
